(kicad_pcb
	(version 20260206)
	(generator "pcbnew")
	(generator_version "10.0")
	(general
		(thickness 1.6)
		(legacy_teardrops no)
	)
	(paper "A4")
	(title_block
		(title "v1-chassis-manager — T6M_CM_d_v01_1031_1645.brd")
		(comment 1 "Open CloudServer (Microsoft) / footprints 347-353 of 2512")
	)
	(layers
		(0 "F.Cu" signal "TOP")
		(4 "In1.Cu" signal "GND1")
		(6 "In2.Cu" signal "IN1")
		(8 "In3.Cu" signal "VCC1")
		(10 "In4.Cu" signal "VCC2")
		(12 "In5.Cu" signal "GND2")
		(14 "In6.Cu" signal "IN2")
		(16 "In7.Cu" signal "IN3")
		(18 "In8.Cu" signal "GND3")
		(2 "B.Cu" signal "BOTTOM")
		(9 "F.Adhes" user "F.Adhesive")
		(11 "B.Adhes" user "B.Adhesive")
		(13 "F.Paste" user "Package Geometry/Pastemask Top")
		(15 "B.Paste" user "Package Geometry/Pastemask Bottom")
		(5 "F.SilkS" user "Ref Des/Silkscreen Top")
		(7 "B.SilkS" user "Ref Des/Silkscreen Bottom")
		(1 "F.Mask" user "Board Geometry/Soldermask Top")
		(3 "B.Mask" user "Board Geometry/Soldermask Bottom")
		(17 "Dwgs.User" user "User.Drawings")
		(19 "Cmts.User" user "User.Comments")
		(21 "Eco1.User" user "User.Eco1")
		(23 "Eco2.User" user "User.Eco2")
		(25 "Edge.Cuts" user "Board Geometry/Outline")
		(27 "Margin" user)
		(31 "F.CrtYd" user "Package Geometry/Place Bound Top")
		(29 "B.CrtYd" user "Package Geometry/Place Bound Bottom")
		(35 "F.Fab" user "Ref Des/Assembly Top")
		(33 "B.Fab" user "Ref Des/Assembly Bottom")
	)
	(footprint ""
		(layer "F.Cu")
		(at 45.604176 -106.255312 180)
		(property "Reference" "PJ2"
			(at 3.070098 -2.106676 90)
			(unlocked yes)
			(layer "F.SilkS")
			(effects
				(font
					(size 0.7874 0.5842)
					(thickness 0.1524)
				)
				(justify left)
			)
		)
		(property "Value" ""
			(at 0 0 180)
			(layer "F.Fab")
			(effects
				(font
					(size 1.27 1.27)
				)
			)
		)
		(duplicate_pad_numbers_are_jumpers no)
		(fp_poly
			(pts
				(xy 0.2794 0.907796) (xy 0.254 0.907796) (xy 0.254 1.0414) (xy -0.254 1.0414) (xy -0.254 1.034796)
				(xy -0.254 0.933196) (xy -0.2794 0.933196) (xy -0.2794 -0.133604) (xy -0.254 -0.133604) (xy -0.254 -0.235204)
				(xy 0.254 -0.235204) (xy 0.254 -0.133604) (xy 0.2794 -0.133604)
			)
			(stroke
				(width 0)
				(type default)
			)
			(fill no)
			(layer "F.CrtYd")
		)
		(pad "1" smd custom
			(at 0 -0.000254 180)
			(size 0.127 0.127)
			(layers "F.Cu" "F.Mask" "F.Paste")
			(net "PWRGD_NODE1_P5V_STB_PG")
			(options
				(clearance outline)
				(anchor circle)
			)
			(primitives
				(gr_poly
					(pts
						(xy -0.127 0.508) (xy -0.127 -0.0508) (xy -0.254 -0.0508) (xy -0.254 -0.508) (xy 0.254 -0.508)
						(xy 0.254 -0.0508) (xy 0.127 -0.0508) (xy 0.127 0.508)
					)
					(width 0)
					(fill yes)
				)
			)
		)
		(pad "2" smd rect
			(at 0 0.799846 270)
			(size 0.4572 0.508)
			(layers "F.Cu" "F.Mask" "F.Paste")
			(net "P3V3_STB_NODE1_EN")
		)
		(zone
			(layer "F.Cu")
			(hatch none 0.5)
			(connect_pads
				(clearance 0)
			)
			(min_thickness 0.25)
			(keepout
				(tracks allowed)
				(vias not_allowed)
				(pads allowed)
				(copperpour not_allowed)
				(footprints allowed)
			)
			(placement
				(enabled no)
				(sheetname "")
			)
			(fill
				(thermal_gap 0.5)
				(thermal_bridge_width 0.5)
				(island_removal_mode 0)
			)
			(polygon
				(pts
					(xy 45.908976 -107.340908) (xy 45.299376 -107.340908) (xy 45.299376 -105.969308) (xy 45.908976 -105.969308)
				)
			)
		)
	)
	(footprint ""
		(layer "F.Cu")
		(at 24.826722 -57.362344 180)
		(property "Reference" "R658"
			(at -12.358878 -3.551936 0)
			(unlocked yes)
			(layer "F.SilkS")
			(effects
				(font
					(size 0.7874 0.5842)
					(thickness 0.1524)
				)
				(justify left)
			)
		)
		(property "Value" ""
			(at 0 0 180)
			(layer "F.Fab")
			(effects
				(font
					(size 1.27 1.27)
				)
			)
		)
		(duplicate_pad_numbers_are_jumpers no)
		(fp_line
			(start 0.7874 0.4064)
			(end -0.7874 0.4064)
			(stroke
				(width 0.1524)
				(type default)
			)
			(layer "F.SilkS")
		)
		(fp_line
			(start 0.7874 -0.4064)
			(end 0.7874 0.4064)
			(stroke
				(width 0.1524)
				(type default)
			)
			(layer "F.SilkS")
		)
		(fp_line
			(start -0.7874 0.4064)
			(end -0.7874 -0.4064)
			(stroke
				(width 0.1524)
				(type default)
			)
			(layer "F.SilkS")
		)
		(fp_line
			(start -0.7874 -0.4064)
			(end 0.7874 -0.4064)
			(stroke
				(width 0.1524)
				(type default)
			)
			(layer "F.SilkS")
		)
		(fp_poly
			(pts
				(xy -0.508 0.2794) (xy -0.508 0.2286) (xy -0.635 0.2286) (xy -0.635 -0.254) (xy -0.5334 -0.254)
				(xy -0.5334 -0.2794) (xy 0.5334 -0.2794) (xy 0.5334 -0.254) (xy 0.635 -0.254) (xy 0.635 0.254) (xy 0.5334 0.254)
				(xy 0.5334 0.2794)
			)
			(stroke
				(width 0)
				(type default)
			)
			(fill no)
			(layer "F.CrtYd")
		)
		(pad "1" smd rect
			(at 0.40005 0 180)
			(size 0.4572 0.508)
			(layers "F.Cu" "F.Mask" "F.Paste")
			(net "GND")
		)
		(pad "2" smd rect
			(at -0.40005 0 180)
			(size 0.4572 0.508)
			(layers "F.Cu" "F.Mask" "F.Paste")
			(net "GFX_BUF_EN_N")
		)
	)
	(footprint ""
		(layer "F.Cu")
		(at 152.755854 -137.187432)
		(property "Reference" "R1063"
			(at -5.190236 1.965198 0)
			(unlocked yes)
			(layer "F.SilkS")
			(effects
				(font
					(size 0.7874 0.5842)
					(thickness 0.1524)
				)
				(justify left)
			)
		)
		(property "Value" ""
			(at 0 0 0)
			(layer "F.Fab")
			(effects
				(font
					(size 1.27 1.27)
				)
			)
		)
		(duplicate_pad_numbers_are_jumpers no)
		(fp_line
			(start -0.7874 -0.4064)
			(end 0.7874 -0.4064)
			(stroke
				(width 0.1524)
				(type default)
			)
			(layer "F.SilkS")
		)
		(fp_line
			(start -0.7874 0.4064)
			(end -0.7874 -0.4064)
			(stroke
				(width 0.1524)
				(type default)
			)
			(layer "F.SilkS")
		)
		(fp_line
			(start 0.7874 -0.4064)
			(end 0.7874 0.4064)
			(stroke
				(width 0.1524)
				(type default)
			)
			(layer "F.SilkS")
		)
		(fp_line
			(start 0.7874 0.4064)
			(end -0.7874 0.4064)
			(stroke
				(width 0.1524)
				(type default)
			)
			(layer "F.SilkS")
		)
		(fp_poly
			(pts
				(xy -0.508 0.2794) (xy -0.508 0.2286) (xy -0.635 0.2286) (xy -0.635 -0.254) (xy -0.5334 -0.254)
				(xy -0.5334 -0.2794) (xy 0.5334 -0.2794) (xy 0.5334 -0.254) (xy 0.635 -0.254) (xy 0.635 0.254) (xy 0.5334 0.254)
				(xy 0.5334 0.2794)
			)
			(stroke
				(width 0)
				(type default)
			)
			(fill no)
			(layer "F.CrtYd")
		)
		(pad "1" smd rect
			(at 0.40005 0)
			(size 0.4572 0.508)
			(layers "F.Cu" "F.Mask" "F.Paste")
			(net "RST_BTN_NODE1_C_L")
		)
		(pad "2" smd rect
			(at -0.40005 0)
			(size 0.4572 0.508)
			(layers "F.Cu" "F.Mask" "F.Paste")
			(net "RST_BTN_L")
		)
	)
	(footprint ""
		(layer "F.Cu")
		(at 149.277578 -57.249822 -90)
		(property "Reference" "R502"
			(at -14.50213 -26.0858 90)
			(unlocked yes)
			(layer "F.SilkS")
			(effects
				(font
					(size 0.7874 0.5842)
					(thickness 0.1524)
				)
				(justify left)
			)
		)
		(property "Value" ""
			(at 0 0 270)
			(layer "F.Fab")
			(effects
				(font
					(size 1.27 1.27)
				)
			)
		)
		(duplicate_pad_numbers_are_jumpers no)
		(fp_line
			(start -0.7874 0.4064)
			(end -0.7874 -0.4064)
			(stroke
				(width 0.1524)
				(type default)
			)
			(layer "F.SilkS")
		)
		(fp_line
			(start 0.7874 0.4064)
			(end -0.7874 0.4064)
			(stroke
				(width 0.1524)
				(type default)
			)
			(layer "F.SilkS")
		)
		(fp_line
			(start -0.7874 -0.4064)
			(end 0.7874 -0.4064)
			(stroke
				(width 0.1524)
				(type default)
			)
			(layer "F.SilkS")
		)
		(fp_line
			(start 0.7874 -0.4064)
			(end 0.7874 0.4064)
			(stroke
				(width 0.1524)
				(type default)
			)
			(layer "F.SilkS")
		)
		(fp_poly
			(pts
				(xy -0.508 0.2794) (xy -0.508 0.2286) (xy -0.635 0.2286) (xy -0.635 -0.254) (xy -0.5334 -0.254)
				(xy -0.5334 -0.2794) (xy 0.5334 -0.2794) (xy 0.5334 -0.254) (xy 0.635 -0.254) (xy 0.635 0.254) (xy 0.5334 0.254)
				(xy 0.5334 0.2794)
			)
			(stroke
				(width 0)
				(type default)
			)
			(fill no)
			(layer "F.CrtYd")
		)
		(pad "1" smd rect
			(at 0.40005 0 270)
			(size 0.4572 0.508)
			(layers "F.Cu" "F.Mask" "F.Paste")
			(net "P3V3_NODE1")
		)
		(pad "2" smd rect
			(at -0.40005 0 270)
			(size 0.4572 0.508)
			(layers "F.Cu" "F.Mask" "F.Paste")
			(net "PU_SATA_NODE1_GPIO4")
		)
	)
	(footprint ""
		(layer "F.Cu")
		(at 115.382802 -22.305264 180)
		(property "Reference" "U123"
			(at 2.883154 -1.497584 90)
			(unlocked yes)
			(layer "F.SilkS")
			(effects
				(font
					(size 0.7874 0.5842)
					(thickness 0.1524)
				)
				(justify left)
			)
		)
		(property "Value" ""
			(at 0 0 180)
			(layer "F.Fab")
			(effects
				(font
					(size 1.27 1.27)
				)
			)
		)
		(duplicate_pad_numbers_are_jumpers no)
		(fp_line
			(start 1.625092 1.625092)
			(end 1.27 1.625092)
			(stroke
				(width 0.1524)
				(type default)
			)
			(layer "F.SilkS")
		)
		(fp_line
			(start 1.625092 1.016)
			(end 1.625092 1.625092)
			(stroke
				(width 0.1524)
				(type default)
			)
			(layer "F.SilkS")
		)
		(fp_line
			(start 1.625092 -1.625092)
			(end 1.625092 -1.016)
			(stroke
				(width 0.1524)
				(type default)
			)
			(layer "F.SilkS")
		)
		(fp_line
			(start 1.27 -1.625092)
			(end 1.625092 -1.625092)
			(stroke
				(width 0.1524)
				(type default)
			)
			(layer "F.SilkS")
		)
		(fp_line
			(start -1.27 1.625092)
			(end -1.625092 1.625092)
			(stroke
				(width 0.1524)
				(type default)
			)
			(layer "F.SilkS")
		)
		(fp_line
			(start -1.625092 1.625092)
			(end -1.625092 1.016)
			(stroke
				(width 0.1524)
				(type default)
			)
			(layer "F.SilkS")
		)
		(fp_line
			(start -1.625092 -1.016)
			(end -1.625092 -1.625092)
			(stroke
				(width 0.1524)
				(type default)
			)
			(layer "F.SilkS")
		)
		(fp_line
			(start -1.625092 -1.625092)
			(end -1.27 -1.625092)
			(stroke
				(width 0.1524)
				(type default)
			)
			(layer "F.SilkS")
		)
		(fp_poly
			(pts
				(xy -0.999998 2.0701) (xy -1.299972 2.970276) (xy -0.700024 2.970276)
			)
			(stroke
				(width 0)
				(type default)
			)
			(fill yes)
			(layer "F.SilkS")
		)
		(fp_poly
			(pts
				(xy -1.625092 1.625092) (xy -1.1938 1.625092) (xy -1.1938 2.0574) (xy 1.1938 2.0574) (xy 1.1938 1.625092)
				(xy 1.625092 1.625092) (xy 1.625092 0.9398) (xy 1.6764 0.9398) (xy 1.6764 -0.9398) (xy 1.625092 -0.9398)
				(xy 1.625092 -1.625092) (xy 1.1938 -1.625092) (xy 1.1938 -2.0574) (xy -1.1938 -2.0574) (xy -1.1938 -1.625092)
				(xy -1.625092 -1.625092) (xy -1.625092 -0.9398) (xy -1.6764 -0.9398) (xy -1.6764 0.9398) (xy -1.625092 0.9398)
			)
			(stroke
				(width 0)
				(type default)
			)
			(fill no)
			(layer "F.CrtYd")
		)
		(fp_line
			(start 1.625092 1.625092)
			(end -1.625092 1.625092)
			(stroke
				(width 0.1)
				(type default)
			)
			(layer "F.Fab")
		)
		(fp_line
			(start 1.625092 -1.625092)
			(end 1.625092 1.625092)
			(stroke
				(width 0.1)
				(type default)
			)
			(layer "F.Fab")
		)
		(fp_line
			(start -1.625092 1.625092)
			(end -1.625092 -1.625092)
			(stroke
				(width 0.1)
				(type default)
			)
			(layer "F.Fab")
		)
		(fp_line
			(start -1.625092 -1.625092)
			(end 1.625092 -1.625092)
			(stroke
				(width 0.1)
				(type default)
			)
			(layer "F.Fab")
		)
		(fp_poly
			(pts
				(xy -0.999998 2.0701) (xy -1.302512 2.977896) (xy -0.697484 2.977896)
			)
			(stroke
				(width 0)
				(type default)
			)
			(fill yes)
			(layer "F.Fab")
		)
		(fp_text user "5"
			(at 2.31013 1.737868 0)
			(unlocked yes)
			(layer "F.SilkS")
			(effects
				(font
					(size 0.635 0.4064)
					(thickness 0.1524)
				)
				(justify left)
			)
		)
		(fp_text user "6"
			(at 1.888236 -1.62306 180)
			(unlocked yes)
			(layer "F.SilkS")
			(effects
				(font
					(size 0.635 0.4064)
					(thickness 0.1524)
				)
				(justify left)
			)
		)
		(fp_text user "1"
			(at -1.525778 2.101596 0)
			(unlocked yes)
			(layer "F.SilkS")
			(effects
				(font
					(size 0.635 0.4064)
					(thickness 0.1524)
				)
				(justify left)
			)
		)
		(fp_text user "10"
			(at -1.846072 -1.77673 0)
			(unlocked yes)
			(layer "F.SilkS")
			(effects
				(font
					(size 0.635 0.4064)
					(thickness 0.1524)
				)
				(justify left)
			)
		)
		(fp_text user "5"
			(at 1.1557 2.245868 180)
			(unlocked yes)
			(layer "F.Fab")
			(effects
				(font
					(size 0.7874 0.5842)
					(thickness 0.000001)
				)
				(justify left)
			)
		)
		(fp_text user "6"
			(at 1.1557 -2.17551 180)
			(unlocked yes)
			(layer "F.Fab")
			(effects
				(font
					(size 0.7874 0.5842)
					(thickness 0.000001)
				)
				(justify left)
			)
		)
		(fp_text user "1"
			(at -1.7907 2.245868 180)
			(unlocked yes)
			(layer "F.Fab")
			(effects
				(font
					(size 0.7874 0.5842)
					(thickness 0.000001)
				)
				(justify left)
			)
		)
		(fp_text user "10"
			(at -2.5654 -2.15011 180)
			(unlocked yes)
			(layer "F.Fab")
			(effects
				(font
					(size 0.7874 0.5842)
					(thickness 0.000001)
				)
				(justify left)
			)
		)
		(pad "1" smd rect
			(at -0.999998 1.550162 180)
			(size 0.2794 0.9144)
			(layers "F.Cu" "F.Mask" "F.Paste")
			(net "PV_VTT_DDR_NODE1_REFIN")
		)
		(pad "2" smd rect
			(at -0.500126 1.550162 180)
			(size 0.2794 0.9144)
			(layers "F.Cu" "F.Mask" "F.Paste")
			(net "PV_VDDR_NODE1")
		)
		(pad "3" smd rect
			(at 0 1.550162 180)
			(size 0.2794 0.9144)
			(layers "F.Cu" "F.Mask" "F.Paste")
			(net "PV_VTT_DDR_NODE1")
		)
		(pad "4" smd rect
			(at 0.500126 1.550162 180)
			(size 0.2794 0.9144)
			(layers "F.Cu" "F.Mask" "F.Paste")
			(net "GND")
		)
		(pad "5" smd rect
			(at 0.999998 1.550162)
			(size 0.2794 0.9144)
			(layers "F.Cu" "F.Mask" "F.Paste")
			(net "PV_VTT_DDR_NODE1_VOSNS")
		)
		(pad "6" smd rect
			(at 0.999998 -1.550162)
			(size 0.2794 0.9144)
			(layers "F.Cu" "F.Mask" "F.Paste")
			(net "PV_VTT_DDR_NODE1_REFOUT")
		)
		(pad "7" smd rect
			(at 0.500126 -1.550162 180)
			(size 0.2794 0.9144)
			(layers "F.Cu" "F.Mask" "F.Paste")
			(net "FM_CPLD_NODE1_PVTT_DDR_EN")
		)
		(pad "8" smd rect
			(at 0 -1.550162 180)
			(size 0.2794 0.9144)
			(layers "F.Cu" "F.Mask" "F.Paste")
			(net "GND")
		)
		(pad "9" smd rect
			(at -0.500126 -1.550162 180)
			(size 0.2794 0.9144)
			(layers "F.Cu" "F.Mask" "F.Paste")
			(net "PWRGD_NODE1_PVTT_DDR_PG")
		)
		(pad "10" smd rect
			(at -0.999998 -1.550162 180)
			(size 0.2794 0.9144)
			(layers "F.Cu" "F.Mask" "F.Paste")
			(net "P3V3_STB_NODE1")
		)
		(pad "TH" smd rect
			(at 0 0 270)
			(size 1.7526 3.2512)
			(layers "F.Cu" "F.Mask" "F.Paste")
			(net "GND")
		)
	)
	(footprint ""
		(layer "F.Cu")
		(at 147.98548 -158.594552 -90)
		(property "Reference" "C191"
			(at 0.138684 -0.475488 0)
			(unlocked yes)
			(layer "F.SilkS")
			(effects
				(font
					(size 0.7874 0.5842)
					(thickness 0.1524)
				)
				(justify left)
			)
		)
		(property "Value" ""
			(at 0 0 270)
			(layer "F.Fab")
			(effects
				(font
					(size 1.27 1.27)
				)
			)
		)
		(duplicate_pad_numbers_are_jumpers no)
		(fp_line
			(start -0.7874 0.4064)
			(end -0.7874 -0.4064)
			(stroke
				(width 0.1524)
				(type default)
			)
			(layer "F.SilkS")
		)
		(fp_line
			(start 0.7874 0.4064)
			(end -0.7874 0.4064)
			(stroke
				(width 0.1524)
				(type default)
			)
			(layer "F.SilkS")
		)
		(fp_line
			(start 0 0.381)
			(end 0 -0.381)
			(stroke
				(width 0.1524)
				(type default)
			)
			(layer "F.SilkS")
		)
		(fp_line
			(start -0.7874 -0.4064)
			(end 0.7874 -0.4064)
			(stroke
				(width 0.1524)
				(type default)
			)
			(layer "F.SilkS")
		)
		(fp_line
			(start 0.7874 -0.4064)
			(end 0.7874 0.4064)
			(stroke
				(width 0.1524)
				(type default)
			)
			(layer "F.SilkS")
		)
		(fp_poly
			(pts
				(xy -0.5334 0.254) (xy -0.635 0.254) (xy -0.635 0.2286) (xy -0.635 -0.254) (xy -0.5334 -0.254) (xy -0.5334 -0.2794)
				(xy 0.5334 -0.2794) (xy 0.5334 -0.254) (xy 0.635 -0.254) (xy 0.635 0.254) (xy 0.5334 0.254) (xy 0.5334 0.2794)
				(xy -0.508 0.2794) (xy -0.5334 0.2794)
			)
			(stroke
				(width 0)
				(type default)
			)
			(fill no)
			(layer "F.CrtYd")
		)
		(pad "1" smd rect
			(at 0.40005 0 270)
			(size 0.4572 0.508)
			(layers "F.Cu" "F.Mask" "F.Paste")
			(net "P3V3_NODE1")
		)
		(pad "2" smd rect
			(at -0.40005 0 270)
			(size 0.4572 0.508)
			(layers "F.Cu" "F.Mask" "F.Paste")
			(net "GND")
		)
	)
	(footprint ""
		(layer "F.Cu")
		(at 154.551126 -165.245288)
		(property "Reference" "R585"
			(at -5.148834 -4.59359 0)
			(unlocked yes)
			(layer "F.SilkS")
			(effects
				(font
					(size 0.7874 0.5842)
					(thickness 0.1524)
				)
				(justify left)
			)
		)
		(property "Value" ""
			(at 0 0 0)
			(layer "F.Fab")
			(effects
				(font
					(size 1.27 1.27)
				)
			)
		)
		(duplicate_pad_numbers_are_jumpers no)
		(fp_line
			(start -0.7874 -0.4064)
			(end 0.7874 -0.4064)
			(stroke
				(width 0.1524)
				(type default)
			)
			(layer "F.SilkS")
		)
		(fp_line
			(start -0.7874 0.4064)
			(end -0.7874 -0.4064)
			(stroke
				(width 0.1524)
				(type default)
			)
			(layer "F.SilkS")
		)
		(fp_line
			(start 0.7874 -0.4064)
			(end 0.7874 0.4064)
			(stroke
				(width 0.1524)
				(type default)
			)
			(layer "F.SilkS")
		)
		(fp_line
			(start 0.7874 0.4064)
			(end -0.7874 0.4064)
			(stroke
				(width 0.1524)
				(type default)
			)
			(layer "F.SilkS")
		)
		(fp_poly
			(pts
				(xy -0.508 0.2794) (xy -0.508 0.2286) (xy -0.635 0.2286) (xy -0.635 -0.254) (xy -0.5334 -0.254)
				(xy -0.5334 -0.2794) (xy 0.5334 -0.2794) (xy 0.5334 -0.254) (xy 0.635 -0.254) (xy 0.635 0.254) (xy 0.5334 0.254)
				(xy 0.5334 0.2794)
			)
			(stroke
				(width 0)
				(type default)
			)
			(fill no)
			(layer "F.CrtYd")
		)
		(pad "1" smd rect
			(at 0.40005 0)
			(size 0.4572 0.508)
			(layers "F.Cu" "F.Mask" "F.Paste")
			(net "LAN2_NVM_WP_N")
		)
		(pad "2" smd rect
			(at -0.40005 0)
			(size 0.4572 0.508)
			(layers "F.Cu" "F.Mask" "F.Paste")
			(net "P3V3_NODE1")
		)
	)
)
